(kicad_pcb
	(version 20260206)
	(generator "pcbnew")
	(generator_version "10.0")
	(general
		(thickness 1.6)
		(legacy_teardrops no)
	)
	(paper "A4")
	(title_block
		(title "03242023_DA0F0TMBIJ0_F0T_Motherboard_J_brd_V01_OCP.brd")
		(comment 1 "Grand Teton / footprints 948-949 of 6105")
	)
	(layers
		(0 "F.Cu" signal "TOP")
		(4 "In1.Cu" signal "GND")
		(6 "In2.Cu" signal "IN1")
		(8 "In3.Cu" signal "GND1")
		(10 "In4.Cu" signal "IN2")
		(12 "In5.Cu" signal "GND2")
		(14 "In6.Cu" signal "IN3")
		(16 "In7.Cu" signal "GND3")
		(18 "In8.Cu" signal "VCC")
		(20 "In9.Cu" signal "VCC1")
		(22 "In10.Cu" signal "GND4")
		(24 "In11.Cu" signal "IN4")
		(26 "In12.Cu" signal "GND5")
		(28 "In13.Cu" signal "IN5")
		(30 "In14.Cu" signal "GND6")
		(32 "In15.Cu" signal "IN6")
		(34 "In16.Cu" signal "GND7")
		(2 "B.Cu" signal "BOTTOM")
		(9 "F.Adhes" user "F.Adhesive")
		(11 "B.Adhes" user "B.Adhesive")
		(13 "F.Paste" user "Package Geometry/Pastemask Top")
		(15 "B.Paste" user "Package Geometry/Pastemask Bottom")
		(5 "F.SilkS" user "Ref Des/Silkscreen Top")
		(7 "B.SilkS" user "Ref Des/Silkscreen Bottom")
		(1 "F.Mask" user "Board Geometry/Soldermask Top")
		(3 "B.Mask" user "Board Geometry/Soldermask Bottom")
		(17 "Dwgs.User" user "User.Drawings")
		(19 "Cmts.User" user "User.Comments")
		(21 "Eco1.User" user "User.Eco1")
		(23 "Eco2.User" user "User.Eco2")
		(25 "Edge.Cuts" user "Board Geometry/Outline")
		(27 "Margin" user)
		(31 "F.CrtYd" user "Package Geometry/Place Bound Top")
		(29 "B.CrtYd" user "Package Geometry/Place Bound Bottom")
		(35 "F.Fab" user "Ref Des/Assembly Top")
		(33 "B.Fab" user "Ref Des/Assembly Bottom")
	)
	(footprint ""
		(layer "F.Cu")
		(at 39.827454 -106.015282 180)
		(property "Reference" "R3688"
			(at 0 0 180)
			(layer "F.SilkS")
			(hide yes)
			(effects
				(font
					(size 1.27 1.27)
				)
			)
		)
		(property "Value" ""
			(at 0 0 180)
			(layer "F.Fab")
			(effects
				(font
					(size 1.27 1.27)
				)
			)
		)
		(duplicate_pad_numbers_are_jumpers no)
		(fp_line
			(start 0.7874 0.4064)
			(end -0.7874 0.4064)
			(stroke
				(width 0.1524)
				(type default)
			)
			(layer "F.SilkS")
		)
		(fp_line
			(start 0.7874 -0.4064)
			(end 0.7874 0.4064)
			(stroke
				(width 0.1524)
				(type default)
			)
			(layer "F.SilkS")
		)
		(fp_line
			(start -0.7874 0.4064)
			(end -0.7874 -0.4064)
			(stroke
				(width 0.1524)
				(type default)
			)
			(layer "F.SilkS")
		)
		(fp_line
			(start -0.7874 -0.4064)
			(end 0.7874 -0.4064)
			(stroke
				(width 0.1524)
				(type default)
			)
			(layer "F.SilkS")
		)
		(fp_line
			(start 0.67945 0.3048)
			(end 0.120396 0.3048)
			(stroke
				(width 0.1)
				(type default)
			)
			(layer "F.Fab")
		)
		(fp_line
			(start 0.67945 -0.3048)
			(end 0.67945 0.3048)
			(stroke
				(width 0.1)
				(type default)
			)
			(layer "F.Fab")
		)
		(fp_line
			(start 0.12065 -0.2794)
			(end 0.12065 -0.3048)
			(stroke
				(width 0.1)
				(type default)
			)
			(layer "F.Fab")
		)
		(fp_line
			(start 0.12065 -0.3048)
			(end 0.67945 -0.3048)
			(stroke
				(width 0.1)
				(type default)
			)
			(layer "F.Fab")
		)
		(fp_line
			(start 0.120396 0.3048)
			(end 0.120396 0.2794)
			(stroke
				(width 0.1)
				(type default)
			)
			(layer "F.Fab")
		)
		(fp_line
			(start 0.120396 0.2794)
			(end -0.12065 0.2794)
			(stroke
				(width 0.1)
				(type default)
			)
			(layer "F.Fab")
		)
		(fp_line
			(start -0.12065 0.3048)
			(end -0.67945 0.3048)
			(stroke
				(width 0.1)
				(type default)
			)
			(layer "F.Fab")
		)
		(fp_line
			(start -0.12065 0.2794)
			(end -0.12065 0.3048)
			(stroke
				(width 0.1)
				(type default)
			)
			(layer "F.Fab")
		)
		(fp_line
			(start -0.12065 -0.2794)
			(end 0.12065 -0.2794)
			(stroke
				(width 0.1)
				(type default)
			)
			(layer "F.Fab")
		)
		(fp_line
			(start -0.12065 -0.305054)
			(end -0.12065 -0.2794)
			(stroke
				(width 0.1)
				(type default)
			)
			(layer "F.Fab")
		)
		(fp_line
			(start -0.67945 0.3048)
			(end -0.67945 -0.305054)
			(stroke
				(width 0.1)
				(type default)
			)
			(layer "F.Fab")
		)
		(fp_line
			(start -0.67945 -0.305054)
			(end -0.12065 -0.305054)
			(stroke
				(width 0.1)
				(type default)
			)
			(layer "F.Fab")
		)
		(pad "1" smd rect
			(at -0.40005 0)
			(size 0.4572 0.508)
			(layers "F.Cu" "F.Mask" "F.Paste")
			(net "P1V581_PDB_ADC")
		)
		(pad "2" smd rect
			(at 0.40005 0)
			(size 0.4572 0.508)
			(layers "F.Cu" "F.Mask" "F.Paste")
			(net "P3V3_PDB_AUX_ADC_TIC")
		)
	)
	(footprint ""
		(layer "F.Cu")
		(at 257.85953 -57.511442 180)
		(property "Reference" "R3974"
			(at 0 0 180)
			(layer "F.SilkS")
			(hide yes)
			(effects
				(font
					(size 1.27 1.27)
				)
			)
		)
		(property "Value" ""
			(at 0 0 180)
			(layer "F.Fab")
			(effects
				(font
					(size 1.27 1.27)
				)
			)
		)
		(duplicate_pad_numbers_are_jumpers no)
		(fp_line
			(start 0.7874 0.4064)
			(end -0.7874 0.4064)
			(stroke
				(width 0.1524)
				(type default)
			)
			(layer "F.SilkS")
		)
		(fp_line
			(start 0.7874 -0.4064)
			(end 0.7874 0.4064)
			(stroke
				(width 0.1524)
				(type default)
			)
			(layer "F.SilkS")
		)
		(fp_line
			(start -0.7874 0.4064)
			(end -0.7874 -0.4064)
			(stroke
				(width 0.1524)
				(type default)
			)
			(layer "F.SilkS")
		)
		(fp_line
			(start -0.7874 -0.4064)
			(end 0.7874 -0.4064)
			(stroke
				(width 0.1524)
				(type default)
			)
			(layer "F.SilkS")
		)
		(fp_line
			(start 0.67945 0.3048)
			(end 0.120396 0.3048)
			(stroke
				(width 0.1)
				(type default)
			)
			(layer "F.Fab")
		)
		(fp_line
			(start 0.67945 -0.3048)
			(end 0.67945 0.3048)
			(stroke
				(width 0.1)
				(type default)
			)
			(layer "F.Fab")
		)
		(fp_line
			(start 0.12065 -0.2794)
			(end 0.12065 -0.3048)
			(stroke
				(width 0.1)
				(type default)
			)
			(layer "F.Fab")
		)
		(fp_line
			(start 0.12065 -0.3048)
			(end 0.67945 -0.3048)
			(stroke
				(width 0.1)
				(type default)
			)
			(layer "F.Fab")
		)
		(fp_line
			(start 0.120396 0.3048)
			(end 0.120396 0.2794)
			(stroke
				(width 0.1)
				(type default)
			)
			(layer "F.Fab")
		)
		(fp_line
			(start 0.120396 0.2794)
			(end -0.12065 0.2794)
			(stroke
				(width 0.1)
				(type default)
			)
			(layer "F.Fab")
		)
		(fp_line
			(start -0.12065 0.3048)
			(end -0.67945 0.3048)
			(stroke
				(width 0.1)
				(type default)
			)
			(layer "F.Fab")
		)
		(fp_line
			(start -0.12065 0.2794)
			(end -0.12065 0.3048)
			(stroke
				(width 0.1)
				(type default)
			)
			(layer "F.Fab")
		)
		(fp_line
			(start -0.12065 -0.2794)
			(end 0.12065 -0.2794)
			(stroke
				(width 0.1)
				(type default)
			)
			(layer "F.Fab")
		)
		(fp_line
			(start -0.12065 -0.305054)
			(end -0.12065 -0.2794)
			(stroke
				(width 0.1)
				(type default)
			)
			(layer "F.Fab")
		)
		(fp_line
			(start -0.67945 0.3048)
			(end -0.67945 -0.305054)
			(stroke
				(width 0.1)
				(type default)
			)
			(layer "F.Fab")
		)
		(fp_line
			(start -0.67945 -0.305054)
			(end -0.12065 -0.305054)
			(stroke
				(width 0.1)
				(type default)
			)
			(layer "F.Fab")
		)
		(pad "1" smd rect
			(at -0.40005 0)
			(size 0.4572 0.508)
			(layers "F.Cu" "F.Mask" "F.Paste")
			(net "P12V_E1S_SENSE_0")
		)
		(pad "2" smd rect
			(at 0.40005 0)
			(size 0.4572 0.508)
			(layers "F.Cu" "F.Mask" "F.Paste")
			(net "P12V_E1S_0_ISENSE_MAM_MAM")
		)
	)
)
